(kicad_pcb
	(version 20260206)
	(generator "pcbnew")
	(generator_version "10.0")
	(general
		(thickness 1.6)
		(legacy_teardrops no)
	)
	(paper "A4")
	(title_block
		(title "Wiwynn_Tioga_Pass_MB.brd")
		(comment 1 "Tioga Pass / footprint 4129 of 4770 (J6L1), pads 1-123 of 291")
	)
	(layers
		(0 "F.Cu" signal "TOP")
		(4 "In1.Cu" signal "L2GND")
		(6 "In2.Cu" signal "L3")
		(8 "In3.Cu" signal "L4GND")
		(10 "In4.Cu" signal "L5")
		(12 "In5.Cu" signal "L6GND")
		(14 "In6.Cu" signal "L7VCC")
		(16 "In7.Cu" signal "L8VCC")
		(18 "In8.Cu" signal "L9GND")
		(20 "In9.Cu" signal "L10")
		(22 "In10.Cu" signal "L11GND")
		(24 "In11.Cu" signal "L12")
		(26 "In12.Cu" signal "L13GND")
		(2 "B.Cu" signal "BOTTOM")
		(9 "F.Adhes" user "F.Adhesive")
		(11 "B.Adhes" user "B.Adhesive")
		(13 "F.Paste" user "Package Geometry/Pastemask Top")
		(15 "B.Paste" user "Package Geometry/Pastemask Bottom")
		(5 "F.SilkS" user "Ref Des/Silkscreen Top")
		(7 "B.SilkS" user "Ref Des/Silkscreen Bottom")
		(1 "F.Mask" user "Board Geometry/Soldermask Top")
		(3 "B.Mask" user "Board Geometry/Soldermask Bottom")
		(17 "Dwgs.User" user "User.Drawings")
		(19 "Cmts.User" user "User.Comments")
		(21 "Eco1.User" user "User.Eco1")
		(23 "Eco2.User" user "User.Eco2")
		(25 "Edge.Cuts" user "Board Geometry/Outline")
		(27 "Margin" user)
		(31 "F.CrtYd" user "Package Geometry/Place Bound Top")
		(29 "B.CrtYd" user "Package Geometry/Place Bound Bottom")
		(35 "F.Fab" user "Ref Des/Assembly Top")
		(33 "B.Fab" user "Ref Des/Assembly Bottom")
	)
	(footprint ""
		(layer "B.Cu")
		(at 194.700398 -152.078436 90)
		(property "Reference" "J6L1"
			(at 2.200148 37.96411 0)
			(unlocked yes)
			(layer "B.SilkS")
			(effects
				(font
					(size 0.7874 0.5842)
					(thickness 0.1524)
				)
				(justify left mirror)
			)
		)
		(property "Value" ""
			(at 0 0 90)
			(layer "B.Fab")
			(effects
				(font
					(size 1.27 1.27)
				)
				(justify mirror)
			)
		)
		(duplicate_pad_numbers_are_jumpers no)
		(pad "" thru_hole circle
			(at -2.29997 -5.649976 270)
			(size 2.8194 2.8194)
			(drill 2.4384)
			(layers "*.Cu" "*.Mask")
			(remove_unused_layers no)
			(clearance 0.127)
			(thermal_gap 0.127)
		)
		(pad "" thru_hole oval
			(at -2.29997 68.90004 270)
			(size 2.8194 1.5748)
			(drill oval 2.4384 1.1938)
			(layers "*.Cu" "*.Mask")
			(remove_unused_layers no)
			(clearance 0.127)
			(thermal_gap 0.127)
		)
		(pad "" thru_hole circle
			(at -2.29997 132.299964 270)
			(size 2.8194 2.8194)
			(drill 2.4384)
			(layers "*.Cu" "*.Mask")
			(remove_unused_layers no)
			(clearance 0.127)
			(thermal_gap 0.127)
		)
		(pad "1" smd rect
			(at 0 0 270)
			(size 1.8034 0.508)
			(layers "B.Cu" "B.Mask" "B.Paste")
			(net "P12V_NVDIMM_DEF")
		)
		(pad "2" smd rect
			(at 0 0.849884 270)
			(size 1.8034 0.508)
			(layers "B.Cu" "B.Mask" "B.Paste")
			(net "GND")
		)
		(pad "3" smd rect
			(at 0 1.700022 270)
			(size 1.8034 0.508)
			(layers "B.Cu" "B.Mask" "B.Paste")
			(net "M_F_DQ<4>")
		)
		(pad "4" smd rect
			(at 0 2.549906 270)
			(size 1.8034 0.508)
			(layers "B.Cu" "B.Mask" "B.Paste")
			(net "GND")
		)
		(pad "5" smd rect
			(at 0 3.400044 270)
			(size 1.8034 0.508)
			(layers "B.Cu" "B.Mask" "B.Paste")
			(net "M_F_DQ<0>")
		)
		(pad "6" smd rect
			(at 0 4.249928 270)
			(size 1.8034 0.508)
			(layers "B.Cu" "B.Mask" "B.Paste")
			(net "GND")
		)
		(pad "7" smd rect
			(at 0 5.100066 270)
			(size 1.8034 0.508)
			(layers "B.Cu" "B.Mask" "B.Paste")
			(net "M_F_DQS_DP<9>")
		)
		(pad "8" smd rect
			(at 0 5.94995 270)
			(size 1.8034 0.508)
			(layers "B.Cu" "B.Mask" "B.Paste")
			(net "M_F_DQS_DN<9>")
		)
		(pad "9" smd rect
			(at 0 6.800088 270)
			(size 1.8034 0.508)
			(layers "B.Cu" "B.Mask" "B.Paste")
			(net "GND")
		)
		(pad "10" smd rect
			(at 0 7.649972 270)
			(size 1.8034 0.508)
			(layers "B.Cu" "B.Mask" "B.Paste")
			(net "M_F_DQ<6>")
		)
		(pad "11" smd rect
			(at 0 8.50011 270)
			(size 1.8034 0.508)
			(layers "B.Cu" "B.Mask" "B.Paste")
			(net "GND")
		)
		(pad "12" smd rect
			(at 0 9.349994 270)
			(size 1.8034 0.508)
			(layers "B.Cu" "B.Mask" "B.Paste")
			(net "M_F_DQ<2>")
		)
		(pad "13" smd rect
			(at 0 10.199878 270)
			(size 1.8034 0.508)
			(layers "B.Cu" "B.Mask" "B.Paste")
			(net "GND")
		)
		(pad "14" smd rect
			(at 0 11.050016 270)
			(size 1.8034 0.508)
			(layers "B.Cu" "B.Mask" "B.Paste")
			(net "M_F_DQ<12>")
		)
		(pad "15" smd rect
			(at 0 11.8999 270)
			(size 1.8034 0.508)
			(layers "B.Cu" "B.Mask" "B.Paste")
			(net "GND")
		)
		(pad "16" smd rect
			(at 0 12.750038 270)
			(size 1.8034 0.508)
			(layers "B.Cu" "B.Mask" "B.Paste")
			(net "M_F_DQ<8>")
		)
		(pad "17" smd rect
			(at 0 13.599922 270)
			(size 1.8034 0.508)
			(layers "B.Cu" "B.Mask" "B.Paste")
			(net "GND")
		)
		(pad "18" smd rect
			(at 0 14.45006 270)
			(size 1.8034 0.508)
			(layers "B.Cu" "B.Mask" "B.Paste")
			(net "M_F_DQS_DP<10>")
		)
		(pad "19" smd rect
			(at 0 15.299944 270)
			(size 1.8034 0.508)
			(layers "B.Cu" "B.Mask" "B.Paste")
			(net "M_F_DQS_DN<10>")
		)
		(pad "20" smd rect
			(at 0 16.150082 270)
			(size 1.8034 0.508)
			(layers "B.Cu" "B.Mask" "B.Paste")
			(net "GND")
		)
		(pad "21" smd rect
			(at 0 16.999966 270)
			(size 1.8034 0.508)
			(layers "B.Cu" "B.Mask" "B.Paste")
			(net "M_F_DQ<14>")
		)
		(pad "22" smd rect
			(at 0 17.850104 270)
			(size 1.8034 0.508)
			(layers "B.Cu" "B.Mask" "B.Paste")
			(net "GND")
		)
		(pad "23" smd rect
			(at 0 18.699988 270)
			(size 1.8034 0.508)
			(layers "B.Cu" "B.Mask" "B.Paste")
			(net "M_F_DQ<10>")
		)
		(pad "24" smd rect
			(at 0 19.550126 270)
			(size 1.8034 0.508)
			(layers "B.Cu" "B.Mask" "B.Paste")
			(net "GND")
		)
		(pad "25" smd rect
			(at 0 20.40001 270)
			(size 1.8034 0.508)
			(layers "B.Cu" "B.Mask" "B.Paste")
			(net "M_F_DQ<20>")
		)
		(pad "26" smd rect
			(at 0 21.249894 270)
			(size 1.8034 0.508)
			(layers "B.Cu" "B.Mask" "B.Paste")
			(net "GND")
		)
		(pad "27" smd rect
			(at 0 22.100032 270)
			(size 1.8034 0.508)
			(layers "B.Cu" "B.Mask" "B.Paste")
			(net "M_F_DQ<16>")
		)
		(pad "28" smd rect
			(at 0 22.949916 270)
			(size 1.8034 0.508)
			(layers "B.Cu" "B.Mask" "B.Paste")
			(net "GND")
		)
		(pad "29" smd rect
			(at 0 23.800054 270)
			(size 1.8034 0.508)
			(layers "B.Cu" "B.Mask" "B.Paste")
			(net "M_F_DQS_DP<11>")
		)
		(pad "30" smd rect
			(at 0 24.649938 270)
			(size 1.8034 0.508)
			(layers "B.Cu" "B.Mask" "B.Paste")
			(net "M_F_DQS_DN<11>")
		)
		(pad "31" smd rect
			(at 0 25.500076 270)
			(size 1.8034 0.508)
			(layers "B.Cu" "B.Mask" "B.Paste")
			(net "GND")
		)
		(pad "32" smd rect
			(at 0 26.34996 270)
			(size 1.8034 0.508)
			(layers "B.Cu" "B.Mask" "B.Paste")
			(net "M_F_DQ<22>")
		)
		(pad "33" smd rect
			(at 0 27.200098 270)
			(size 1.8034 0.508)
			(layers "B.Cu" "B.Mask" "B.Paste")
			(net "GND")
		)
		(pad "34" smd rect
			(at 0 28.049982 270)
			(size 1.8034 0.508)
			(layers "B.Cu" "B.Mask" "B.Paste")
			(net "M_F_DQ<18>")
		)
		(pad "35" smd rect
			(at 0 28.90012 270)
			(size 1.8034 0.508)
			(layers "B.Cu" "B.Mask" "B.Paste")
			(net "GND")
		)
		(pad "36" smd rect
			(at 0 29.750004 270)
			(size 1.8034 0.508)
			(layers "B.Cu" "B.Mask" "B.Paste")
			(net "M_F_DQ<28>")
		)
		(pad "37" smd rect
			(at 0 30.599888 270)
			(size 1.8034 0.508)
			(layers "B.Cu" "B.Mask" "B.Paste")
			(net "GND")
		)
		(pad "38" smd rect
			(at 0 31.450026 270)
			(size 1.8034 0.508)
			(layers "B.Cu" "B.Mask" "B.Paste")
			(net "M_F_DQ<24>")
		)
		(pad "39" smd rect
			(at 0 32.29991 270)
			(size 1.8034 0.508)
			(layers "B.Cu" "B.Mask" "B.Paste")
			(net "GND")
		)
		(pad "40" smd rect
			(at 0 33.150048 270)
			(size 1.8034 0.508)
			(layers "B.Cu" "B.Mask" "B.Paste")
			(net "M_F_DQS_DP<12>")
		)
		(pad "41" smd rect
			(at 0 33.999932 270)
			(size 1.8034 0.508)
			(layers "B.Cu" "B.Mask" "B.Paste")
			(net "M_F_DQS_DN<12>")
		)
		(pad "42" smd rect
			(at 0 34.85007 270)
			(size 1.8034 0.508)
			(layers "B.Cu" "B.Mask" "B.Paste")
			(net "GND")
		)
		(pad "43" smd rect
			(at 0 35.699954 270)
			(size 1.8034 0.508)
			(layers "B.Cu" "B.Mask" "B.Paste")
			(net "M_F_DQ<30>")
		)
		(pad "44" smd rect
			(at 0 36.550092 270)
			(size 1.8034 0.508)
			(layers "B.Cu" "B.Mask" "B.Paste")
			(net "GND")
		)
		(pad "45" smd rect
			(at 0 37.399976 270)
			(size 1.8034 0.508)
			(layers "B.Cu" "B.Mask" "B.Paste")
			(net "M_F_DQ<26>")
		)
		(pad "46" smd rect
			(at 0 38.250114 270)
			(size 1.8034 0.508)
			(layers "B.Cu" "B.Mask" "B.Paste")
			(net "GND")
		)
		(pad "47" smd rect
			(at 0 39.099998 270)
			(size 1.8034 0.508)
			(layers "B.Cu" "B.Mask" "B.Paste")
			(net "M_F_ECC<4>")
		)
		(pad "48" smd rect
			(at 0 39.949882 270)
			(size 1.8034 0.508)
			(layers "B.Cu" "B.Mask" "B.Paste")
			(net "GND")
		)
		(pad "49" smd rect
			(at 0 40.80002 270)
			(size 1.8034 0.508)
			(layers "B.Cu" "B.Mask" "B.Paste")
			(net "M_F_ECC<0>")
		)
		(pad "50" smd rect
			(at 0 41.649904 270)
			(size 1.8034 0.508)
			(layers "B.Cu" "B.Mask" "B.Paste")
			(net "GND")
		)
		(pad "51" smd rect
			(at 0 42.500042 270)
			(size 1.8034 0.508)
			(layers "B.Cu" "B.Mask" "B.Paste")
			(net "M_F_DQS_DP<17>")
		)
		(pad "52" smd rect
			(at 0 43.349926 270)
			(size 1.8034 0.508)
			(layers "B.Cu" "B.Mask" "B.Paste")
			(net "M_F_DQS_DN<17>")
		)
		(pad "53" smd rect
			(at 0 44.200064 270)
			(size 1.8034 0.508)
			(layers "B.Cu" "B.Mask" "B.Paste")
			(net "GND")
		)
		(pad "54" smd rect
			(at 0 45.049948 270)
			(size 1.8034 0.508)
			(layers "B.Cu" "B.Mask" "B.Paste")
			(net "M_F_ECC<6>")
		)
		(pad "55" smd rect
			(at 0 45.900086 270)
			(size 1.8034 0.508)
			(layers "B.Cu" "B.Mask" "B.Paste")
			(net "GND")
		)
		(pad "56" smd rect
			(at 0 46.74997 270)
			(size 1.8034 0.508)
			(layers "B.Cu" "B.Mask" "B.Paste")
			(net "M_F_ECC<2>")
		)
		(pad "57" smd rect
			(at 0 47.600108 270)
			(size 1.8034 0.508)
			(layers "B.Cu" "B.Mask" "B.Paste")
			(net "GND")
		)
		(pad "58" smd rect
			(at 0 48.449992 270)
			(size 1.8034 0.508)
			(layers "B.Cu" "B.Mask" "B.Paste")
			(net "M_DEF_RST_N")
		)
		(pad "59" smd rect
			(at 0 49.299876 270)
			(size 1.8034 0.508)
			(layers "B.Cu" "B.Mask" "B.Paste")
			(net "PVDDQ_DEF")
		)
		(pad "60" smd rect
			(at 0 50.150014 270)
			(size 1.8034 0.508)
			(layers "B.Cu" "B.Mask" "B.Paste")
			(net "M_F_CKE<2>")
		)
		(pad "61" smd rect
			(at 0 50.999898 270)
			(size 1.8034 0.508)
			(layers "B.Cu" "B.Mask" "B.Paste")
			(net "PVDDQ_DEF")
		)
		(pad "62" smd rect
			(at 0 51.850036 270)
			(size 1.8034 0.508)
			(layers "B.Cu" "B.Mask" "B.Paste")
			(net "M_F_ACT_N")
		)
		(pad "63" smd rect
			(at 0 52.69992 270)
			(size 1.8034 0.508)
			(layers "B.Cu" "B.Mask" "B.Paste")
			(net "M_F_BG<0>")
		)
		(pad "64" smd rect
			(at 0 53.550058 270)
			(size 1.8034 0.508)
			(layers "B.Cu" "B.Mask" "B.Paste")
			(net "PVDDQ_DEF")
		)
		(pad "65" smd rect
			(at 0 54.399942 270)
			(size 1.8034 0.508)
			(layers "B.Cu" "B.Mask" "B.Paste")
			(net "M_F_MA<12>")
		)
		(pad "66" smd rect
			(at 0 55.25008 270)
			(size 1.8034 0.508)
			(layers "B.Cu" "B.Mask" "B.Paste")
			(net "M_F_MA<9>")
		)
		(pad "67" smd rect
			(at 0 56.099964 270)
			(size 1.8034 0.508)
			(layers "B.Cu" "B.Mask" "B.Paste")
			(net "PVDDQ_DEF")
		)
		(pad "68" smd rect
			(at 0 56.950102 270)
			(size 1.8034 0.508)
			(layers "B.Cu" "B.Mask" "B.Paste")
			(net "M_F_MA<8>")
		)
		(pad "69" smd rect
			(at 0 57.799986 270)
			(size 1.8034 0.508)
			(layers "B.Cu" "B.Mask" "B.Paste")
			(net "M_F_MA<6>")
		)
		(pad "70" smd rect
			(at 0 58.650124 270)
			(size 1.8034 0.508)
			(layers "B.Cu" "B.Mask" "B.Paste")
			(net "PVDDQ_DEF")
		)
		(pad "71" smd rect
			(at 0 59.500008 270)
			(size 1.8034 0.508)
			(layers "B.Cu" "B.Mask" "B.Paste")
			(net "M_F_MA<3>")
		)
		(pad "72" smd rect
			(at 0 60.349892 270)
			(size 1.8034 0.508)
			(layers "B.Cu" "B.Mask" "B.Paste")
			(net "M_F_MA<1>")
		)
		(pad "73" smd rect
			(at 0 61.20003 270)
			(size 1.8034 0.508)
			(layers "B.Cu" "B.Mask" "B.Paste")
			(net "PVDDQ_DEF")
		)
		(pad "74" smd rect
			(at 0 62.049914 270)
			(size 1.8034 0.508)
			(layers "B.Cu" "B.Mask" "B.Paste")
			(net "M_F_CLK_DP<2>")
		)
		(pad "75" smd rect
			(at 0 62.900052 270)
			(size 1.8034 0.508)
			(layers "B.Cu" "B.Mask" "B.Paste")
			(net "M_F_CLK_DN<2>")
		)
		(pad "76" smd rect
			(at 0 63.749936 270)
			(size 1.8034 0.508)
			(layers "B.Cu" "B.Mask" "B.Paste")
			(net "PVDDQ_DEF")
		)
		(pad "77" smd rect
			(at 0 64.600074 270)
			(size 1.8034 0.508)
			(layers "B.Cu" "B.Mask" "B.Paste")
			(net "PVTT_DEF")
		)
		(pad "78" smd rect
			(at 0 70.550024 270)
			(size 1.8034 0.508)
			(layers "B.Cu" "B.Mask" "B.Paste")
			(net "FM_DIMM_EVENT_COD_N")
		)
		(pad "79" smd rect
			(at 0 71.399908 270)
			(size 1.8034 0.508)
			(layers "B.Cu" "B.Mask" "B.Paste")
			(net "M_F_MA<0>")
		)
		(pad "80" smd rect
			(at 0 72.250046 270)
			(size 1.8034 0.508)
			(layers "B.Cu" "B.Mask" "B.Paste")
			(net "PVDDQ_DEF")
		)
		(pad "81" smd rect
			(at 0 73.09993 270)
			(size 1.8034 0.508)
			(layers "B.Cu" "B.Mask" "B.Paste")
			(net "M_F_BA<0>")
		)
		(pad "82" smd rect
			(at 0 73.950068 270)
			(size 1.8034 0.508)
			(layers "B.Cu" "B.Mask" "B.Paste")
			(net "M_F_MA<16>")
		)
		(pad "83" smd rect
			(at 0 74.799952 270)
			(size 1.8034 0.508)
			(layers "B.Cu" "B.Mask" "B.Paste")
			(net "PVDDQ_DEF")
		)
		(pad "84" smd rect
			(at 0 75.65009 270)
			(size 1.8034 0.508)
			(layers "B.Cu" "B.Mask" "B.Paste")
			(net "M_F_CS_N<4>")
		)
		(pad "85" smd rect
			(at 0 76.499974 270)
			(size 1.8034 0.508)
			(layers "B.Cu" "B.Mask" "B.Paste")
			(net "PVDDQ_DEF")
		)
		(pad "86" smd rect
			(at 0 77.350112 270)
			(size 1.8034 0.508)
			(layers "B.Cu" "B.Mask" "B.Paste")
			(net "M_F_MA<15>")
		)
		(pad "87" smd rect
			(at 0 78.199996 270)
			(size 1.8034 0.508)
			(layers "B.Cu" "B.Mask" "B.Paste")
			(net "M_F_ODT<2>")
		)
		(pad "88" smd rect
			(at 0 79.04988 270)
			(size 1.8034 0.508)
			(layers "B.Cu" "B.Mask" "B.Paste")
			(net "PVDDQ_DEF")
		)
		(pad "89" smd rect
			(at 0 79.900018 270)
			(size 1.8034 0.508)
			(layers "B.Cu" "B.Mask" "B.Paste")
			(net "M_F_CS_N<5>")
		)
		(pad "90" smd rect
			(at 0 80.749902 270)
			(size 1.8034 0.508)
			(layers "B.Cu" "B.Mask" "B.Paste")
			(net "PVDDQ_DEF")
		)
		(pad "91" smd rect
			(at 0 81.60004 270)
			(size 1.8034 0.508)
			(layers "B.Cu" "B.Mask" "B.Paste")
			(net "M_F_ODT<3>")
		)
		(pad "92" smd rect
			(at 0 82.449924 270)
			(size 1.8034 0.508)
			(layers "B.Cu" "B.Mask" "B.Paste")
			(net "PVDDQ_DEF")
		)
		(pad "93" smd rect
			(at 0 83.300062 270)
			(size 1.8034 0.508)
			(layers "B.Cu" "B.Mask" "B.Paste")
			(net "M_F_CS_N<6>")
		)
		(pad "94" smd rect
			(at 0 84.149946 270)
			(size 1.8034 0.508)
			(layers "B.Cu" "B.Mask" "B.Paste")
			(net "GND")
		)
		(pad "95" smd rect
			(at 0 85.000084 270)
			(size 1.8034 0.508)
			(layers "B.Cu" "B.Mask" "B.Paste")
			(net "M_F_DQ<36>")
		)
		(pad "96" smd rect
			(at 0 85.849968 270)
			(size 1.8034 0.508)
			(layers "B.Cu" "B.Mask" "B.Paste")
			(net "GND")
		)
		(pad "97" smd rect
			(at 0 86.700106 270)
			(size 1.8034 0.508)
			(layers "B.Cu" "B.Mask" "B.Paste")
			(net "M_F_DQ<32>")
		)
		(pad "98" smd rect
			(at 0 87.54999 270)
			(size 1.8034 0.508)
			(layers "B.Cu" "B.Mask" "B.Paste")
			(net "GND")
		)
		(pad "99" smd rect
			(at 0 88.399874 270)
			(size 1.8034 0.508)
			(layers "B.Cu" "B.Mask" "B.Paste")
			(net "M_F_DQS_DP<13>")
		)
		(pad "100" smd rect
			(at 0 89.250012 270)
			(size 1.8034 0.508)
			(layers "B.Cu" "B.Mask" "B.Paste")
			(net "M_F_DQS_DN<13>")
		)
		(pad "101" smd rect
			(at 0 90.099896 270)
			(size 1.8034 0.508)
			(layers "B.Cu" "B.Mask" "B.Paste")
			(net "GND")
		)
		(pad "102" smd rect
			(at 0 90.950034 270)
			(size 1.8034 0.508)
			(layers "B.Cu" "B.Mask" "B.Paste")
			(net "M_F_DQ<38>")
		)
		(pad "103" smd rect
			(at 0 91.799918 270)
			(size 1.8034 0.508)
			(layers "B.Cu" "B.Mask" "B.Paste")
			(net "GND")
		)
		(pad "104" smd rect
			(at 0 92.650056 270)
			(size 1.8034 0.508)
			(layers "B.Cu" "B.Mask" "B.Paste")
			(net "M_F_DQ<34>")
		)
		(pad "105" smd rect
			(at 0 93.49994 270)
			(size 1.8034 0.508)
			(layers "B.Cu" "B.Mask" "B.Paste")
			(net "GND")
		)
		(pad "106" smd rect
			(at 0 94.350078 270)
			(size 1.8034 0.508)
			(layers "B.Cu" "B.Mask" "B.Paste")
			(net "M_F_DQ<44>")
		)
		(pad "107" smd rect
			(at 0 95.199962 270)
			(size 1.8034 0.508)
			(layers "B.Cu" "B.Mask" "B.Paste")
			(net "GND")
		)
		(pad "108" smd rect
			(at 0 96.0501 270)
			(size 1.8034 0.508)
			(layers "B.Cu" "B.Mask" "B.Paste")
			(net "M_F_DQ<40>")
		)
		(pad "109" smd rect
			(at 0 96.899984 270)
			(size 1.8034 0.508)
			(layers "B.Cu" "B.Mask" "B.Paste")
			(net "GND")
		)
		(pad "110" smd rect
			(at 0 97.750122 270)
			(size 1.8034 0.508)
			(layers "B.Cu" "B.Mask" "B.Paste")
			(net "M_F_DQS_DP<14>")
		)
		(pad "111" smd rect
			(at 0 98.600006 270)
			(size 1.8034 0.508)
			(layers "B.Cu" "B.Mask" "B.Paste")
			(net "M_F_DQS_DN<14>")
		)
		(pad "112" smd rect
			(at 0 99.44989 270)
			(size 1.8034 0.508)
			(layers "B.Cu" "B.Mask" "B.Paste")
			(net "GND")
		)
		(pad "113" smd rect
			(at 0 100.300028 270)
			(size 1.8034 0.508)
			(layers "B.Cu" "B.Mask" "B.Paste")
			(net "M_F_DQ<46>")
		)
		(pad "114" smd rect
			(at 0 101.149912 270)
			(size 1.8034 0.508)
			(layers "B.Cu" "B.Mask" "B.Paste")
			(net "GND")
		)
		(pad "115" smd rect
			(at 0 102.00005 270)
			(size 1.8034 0.508)
			(layers "B.Cu" "B.Mask" "B.Paste")
			(net "M_F_DQ<42>")
		)
		(pad "116" smd rect
			(at 0 102.849934 270)
			(size 1.8034 0.508)
			(layers "B.Cu" "B.Mask" "B.Paste")
			(net "GND")
		)
		(pad "117" smd rect
			(at 0 103.700072 270)
			(size 1.8034 0.508)
			(layers "B.Cu" "B.Mask" "B.Paste")
			(net "M_F_DQ<52>")
		)
		(pad "118" smd rect
			(at 0 104.549956 270)
			(size 1.8034 0.508)
			(layers "B.Cu" "B.Mask" "B.Paste")
			(net "GND")
		)
		(pad "119" smd rect
			(at 0 105.400094 270)
			(size 1.8034 0.508)
			(layers "B.Cu" "B.Mask" "B.Paste")
			(net "M_F_DQ<48>")
		)
		(pad "120" smd rect
			(at 0 106.249978 270)
			(size 1.8034 0.508)
			(layers "B.Cu" "B.Mask" "B.Paste")
			(net "GND")
		)
	)
)
